(kicad_pcb
	(version 20260206)
	(generator "pcbnew")
	(generator_version "10.0")
	(general
		(thickness 1.6)
		(legacy_teardrops no)
	)
	(paper "A4")
	(title_block
		(title "01162023_DA0F0TEBIF0_F0T_Expander_BD_F_brd_V02_OCP.brd")
		(comment 1 "Grand Teton / footprints 8355-8362 of 9728")
	)
	(layers
		(0 "F.Cu" signal "TOP")
		(4 "In1.Cu" signal "GND")
		(6 "In2.Cu" signal "VCC")
		(8 "In3.Cu" signal "VCC1")
		(10 "In4.Cu" signal "GND1")
		(12 "In5.Cu" signal "IN1")
		(14 "In6.Cu" signal "GND2")
		(16 "In7.Cu" signal "IN2")
		(18 "In8.Cu" signal "GND3")
		(20 "In9.Cu" signal "IN3")
		(22 "In10.Cu" signal "GND4")
		(24 "In11.Cu" signal "IN4")
		(26 "In12.Cu" signal "GND5")
		(28 "In13.Cu" signal "IN5")
		(30 "In14.Cu" signal "GND6")
		(32 "In15.Cu" signal "IN6")
		(34 "In16.Cu" signal "GND7")
		(2 "B.Cu" signal "BOTTOM")
		(9 "F.Adhes" user "F.Adhesive")
		(11 "B.Adhes" user "B.Adhesive")
		(13 "F.Paste" user "Package Geometry/Pastemask Top")
		(15 "B.Paste" user "Package Geometry/Pastemask Bottom")
		(5 "F.SilkS" user "Ref Des/Silkscreen Top")
		(7 "B.SilkS" user "Ref Des/Silkscreen Bottom")
		(1 "F.Mask" user "Board Geometry/Soldermask Top")
		(3 "B.Mask" user "Board Geometry/Soldermask Bottom")
		(17 "Dwgs.User" user "User.Drawings")
		(19 "Cmts.User" user "User.Comments")
		(21 "Eco1.User" user "User.Eco1")
		(23 "Eco2.User" user "User.Eco2")
		(25 "Edge.Cuts" user "Board Geometry/Outline")
		(27 "Margin" user)
		(31 "F.CrtYd" user "Package Geometry/Place Bound Top")
		(29 "B.CrtYd" user "Package Geometry/Place Bound Bottom")
		(35 "F.Fab" user "Ref Des/Assembly Top")
		(33 "B.Fab" user "Ref Des/Assembly Bottom")
	)
	(footprint ""
		(layer "B.Cu")
		(at 281.445462 -296.37482)
		(property "Reference" "C1626"
			(at 0 0 0)
			(layer "B.SilkS")
			(hide yes)
			(effects
				(font
					(size 1.27 1.27)
				)
				(justify mirror)
			)
		)
		(property "Value" ""
			(at 0 0 0)
			(layer "B.Fab")
			(effects
				(font
					(size 1.27 1.27)
				)
				(justify mirror)
			)
		)
		(duplicate_pad_numbers_are_jumpers no)
		(fp_line
			(start -0.299974 -0.150114)
			(end -0.299974 0.150114)
			(stroke
				(width 0.1)
				(type default)
			)
			(layer "B.Fab")
		)
		(fp_line
			(start -0.299974 0.150114)
			(end 0.299974 0.150114)
			(stroke
				(width 0.1)
				(type default)
			)
			(layer "B.Fab")
		)
		(fp_line
			(start 0.299974 -0.150114)
			(end -0.299974 -0.150114)
			(stroke
				(width 0.1)
				(type default)
			)
			(layer "B.Fab")
		)
		(fp_line
			(start 0.299974 0.150114)
			(end 0.299974 -0.150114)
			(stroke
				(width 0.1)
				(type default)
			)
			(layer "B.Fab")
		)
		(pad "1" smd rect
			(at 0.2667 0 180)
			(size 0.3048 0.381)
			(layers "B.Cu" "B.Mask" "B.Paste")
			(net "P0V8_PEX2")
		)
		(pad "2" smd rect
			(at -0.2667 0 180)
			(size 0.3048 0.381)
			(layers "B.Cu" "B.Mask" "B.Paste")
			(net "GND")
		)
	)
	(footprint ""
		(layer "B.Cu")
		(at 105.34269 -326.152256 -90)
		(property "Reference" "R1226"
			(at 0 0 90)
			(layer "B.SilkS")
			(hide yes)
			(effects
				(font
					(size 1.27 1.27)
				)
				(justify mirror)
			)
		)
		(property "Value" ""
			(at 0 0 90)
			(layer "B.Fab")
			(effects
				(font
					(size 1.27 1.27)
				)
				(justify mirror)
			)
		)
		(duplicate_pad_numbers_are_jumpers no)
		(fp_line
			(start -0.7874 0.4064)
			(end 0.7874 0.4064)
			(stroke
				(width 0.1524)
				(type default)
			)
			(layer "B.SilkS")
		)
		(fp_line
			(start 0.7874 0.4064)
			(end 0.7874 -0.4064)
			(stroke
				(width 0.1524)
				(type default)
			)
			(layer "B.SilkS")
		)
		(fp_line
			(start -0.7874 -0.4064)
			(end -0.7874 0.4064)
			(stroke
				(width 0.1524)
				(type default)
			)
			(layer "B.SilkS")
		)
		(fp_line
			(start 0.7874 -0.4064)
			(end -0.7874 -0.4064)
			(stroke
				(width 0.1524)
				(type default)
			)
			(layer "B.SilkS")
		)
		(fp_line
			(start -0.67945 0.3048)
			(end -0.120396 0.3048)
			(stroke
				(width 0.1)
				(type default)
			)
			(layer "B.Fab")
		)
		(fp_line
			(start -0.120396 0.3048)
			(end -0.120396 0.2794)
			(stroke
				(width 0.1)
				(type default)
			)
			(layer "B.Fab")
		)
		(fp_line
			(start 0.12065 0.3048)
			(end 0.67945 0.3048)
			(stroke
				(width 0.1)
				(type default)
			)
			(layer "B.Fab")
		)
		(fp_line
			(start 0.67945 0.3048)
			(end 0.67945 -0.305054)
			(stroke
				(width 0.1)
				(type default)
			)
			(layer "B.Fab")
		)
		(fp_line
			(start -0.120396 0.2794)
			(end 0.12065 0.2794)
			(stroke
				(width 0.1)
				(type default)
			)
			(layer "B.Fab")
		)
		(fp_line
			(start 0.12065 0.2794)
			(end 0.12065 0.3048)
			(stroke
				(width 0.1)
				(type default)
			)
			(layer "B.Fab")
		)
		(fp_line
			(start -0.12065 -0.2794)
			(end -0.12065 -0.3048)
			(stroke
				(width 0.1)
				(type default)
			)
			(layer "B.Fab")
		)
		(fp_line
			(start 0.12065 -0.2794)
			(end -0.12065 -0.2794)
			(stroke
				(width 0.1)
				(type default)
			)
			(layer "B.Fab")
		)
		(fp_line
			(start -0.67945 -0.3048)
			(end -0.67945 0.3048)
			(stroke
				(width 0.1)
				(type default)
			)
			(layer "B.Fab")
		)
		(fp_line
			(start -0.12065 -0.3048)
			(end -0.67945 -0.3048)
			(stroke
				(width 0.1)
				(type default)
			)
			(layer "B.Fab")
		)
		(fp_line
			(start 0.12065 -0.305054)
			(end 0.12065 -0.2794)
			(stroke
				(width 0.1)
				(type default)
			)
			(layer "B.Fab")
		)
		(fp_line
			(start 0.67945 -0.305054)
			(end 0.12065 -0.305054)
			(stroke
				(width 0.1)
				(type default)
			)
			(layer "B.Fab")
		)
		(pad "1" smd circle
			(at 0.40005 0 90)
			(size 0 0)
			(layers "B.Cu" "B.Mask" "B.Paste")
			(net "CLK_100M_DB800ZL_PEX0_S0_R_DN")
		)
		(pad "2" smd circle
			(at -0.40005 0 90)
			(size 0 0)
			(layers "B.Cu" "B.Mask" "B.Paste")
			(net "CLK_100M_DB800ZL_PEX0_S0_DN")
		)
	)
	(footprint ""
		(layer "B.Cu")
		(at 156.219144 -294.8051 180)
		(property "Reference" "R3454"
			(at 0 0 0)
			(layer "B.SilkS")
			(hide yes)
			(effects
				(font
					(size 1.27 1.27)
				)
				(justify mirror)
			)
		)
		(property "Value" ""
			(at 0 0 0)
			(layer "B.Fab")
			(effects
				(font
					(size 1.27 1.27)
				)
				(justify mirror)
			)
		)
		(duplicate_pad_numbers_are_jumpers no)
		(fp_line
			(start 0.7874 0.4064)
			(end 0.7874 -0.4064)
			(stroke
				(width 0.1524)
				(type default)
			)
			(layer "B.SilkS")
		)
		(fp_line
			(start 0.7874 -0.4064)
			(end -0.7874 -0.4064)
			(stroke
				(width 0.1524)
				(type default)
			)
			(layer "B.SilkS")
		)
		(fp_line
			(start -0.7874 0.4064)
			(end 0.7874 0.4064)
			(stroke
				(width 0.1524)
				(type default)
			)
			(layer "B.SilkS")
		)
		(fp_line
			(start -0.7874 -0.4064)
			(end -0.7874 0.4064)
			(stroke
				(width 0.1524)
				(type default)
			)
			(layer "B.SilkS")
		)
		(fp_line
			(start 0.67945 0.3048)
			(end 0.67945 -0.305054)
			(stroke
				(width 0.1)
				(type default)
			)
			(layer "B.Fab")
		)
		(fp_line
			(start 0.67945 -0.305054)
			(end 0.12065 -0.305054)
			(stroke
				(width 0.1)
				(type default)
			)
			(layer "B.Fab")
		)
		(fp_line
			(start 0.12065 0.3048)
			(end 0.67945 0.3048)
			(stroke
				(width 0.1)
				(type default)
			)
			(layer "B.Fab")
		)
		(fp_line
			(start 0.12065 0.2794)
			(end 0.12065 0.3048)
			(stroke
				(width 0.1)
				(type default)
			)
			(layer "B.Fab")
		)
		(fp_line
			(start 0.12065 -0.2794)
			(end -0.12065 -0.2794)
			(stroke
				(width 0.1)
				(type default)
			)
			(layer "B.Fab")
		)
		(fp_line
			(start 0.12065 -0.305054)
			(end 0.12065 -0.2794)
			(stroke
				(width 0.1)
				(type default)
			)
			(layer "B.Fab")
		)
		(fp_line
			(start -0.120396 0.3048)
			(end -0.120396 0.2794)
			(stroke
				(width 0.1)
				(type default)
			)
			(layer "B.Fab")
		)
		(fp_line
			(start -0.120396 0.2794)
			(end 0.12065 0.2794)
			(stroke
				(width 0.1)
				(type default)
			)
			(layer "B.Fab")
		)
		(fp_line
			(start -0.12065 -0.2794)
			(end -0.12065 -0.3048)
			(stroke
				(width 0.1)
				(type default)
			)
			(layer "B.Fab")
		)
		(fp_line
			(start -0.12065 -0.3048)
			(end -0.67945 -0.3048)
			(stroke
				(width 0.1)
				(type default)
			)
			(layer "B.Fab")
		)
		(fp_line
			(start -0.67945 0.3048)
			(end -0.120396 0.3048)
			(stroke
				(width 0.1)
				(type default)
			)
			(layer "B.Fab")
		)
		(fp_line
			(start -0.67945 -0.3048)
			(end -0.67945 0.3048)
			(stroke
				(width 0.1)
				(type default)
			)
			(layer "B.Fab")
		)
		(pad "1" smd circle
			(at 0.40005 0)
			(size 0 0)
			(layers "B.Cu" "B.Mask" "B.Paste")
			(net "SPI_PEX1_SDIO2_R")
		)
		(pad "2" smd circle
			(at -0.40005 0)
			(size 0 0)
			(layers "B.Cu" "B.Mask" "B.Paste")
			(net "SPI_PEX1_SDIO2")
		)
	)
	(footprint ""
		(layer "B.Cu")
		(at 346.583 -207.772 -90)
		(property "Reference" "R4150"
			(at 0 0 90)
			(layer "B.SilkS")
			(hide yes)
			(effects
				(font
					(size 1.27 1.27)
				)
				(justify mirror)
			)
		)
		(property "Value" ""
			(at 0 0 90)
			(layer "B.Fab")
			(effects
				(font
					(size 1.27 1.27)
				)
				(justify mirror)
			)
		)
		(duplicate_pad_numbers_are_jumpers no)
		(fp_line
			(start -0.7874 0.4064)
			(end 0.7874 0.4064)
			(stroke
				(width 0.1524)
				(type default)
			)
			(layer "B.SilkS")
		)
		(fp_line
			(start 0.7874 0.4064)
			(end 0.7874 -0.4064)
			(stroke
				(width 0.1524)
				(type default)
			)
			(layer "B.SilkS")
		)
		(fp_line
			(start -0.7874 -0.4064)
			(end -0.7874 0.4064)
			(stroke
				(width 0.1524)
				(type default)
			)
			(layer "B.SilkS")
		)
		(fp_line
			(start 0.7874 -0.4064)
			(end -0.7874 -0.4064)
			(stroke
				(width 0.1524)
				(type default)
			)
			(layer "B.SilkS")
		)
		(fp_line
			(start -0.67945 0.3048)
			(end -0.120396 0.3048)
			(stroke
				(width 0.1)
				(type default)
			)
			(layer "B.Fab")
		)
		(fp_line
			(start -0.120396 0.3048)
			(end -0.120396 0.2794)
			(stroke
				(width 0.1)
				(type default)
			)
			(layer "B.Fab")
		)
		(fp_line
			(start 0.12065 0.3048)
			(end 0.67945 0.3048)
			(stroke
				(width 0.1)
				(type default)
			)
			(layer "B.Fab")
		)
		(fp_line
			(start 0.67945 0.3048)
			(end 0.67945 -0.305054)
			(stroke
				(width 0.1)
				(type default)
			)
			(layer "B.Fab")
		)
		(fp_line
			(start -0.120396 0.2794)
			(end 0.12065 0.2794)
			(stroke
				(width 0.1)
				(type default)
			)
			(layer "B.Fab")
		)
		(fp_line
			(start 0.12065 0.2794)
			(end 0.12065 0.3048)
			(stroke
				(width 0.1)
				(type default)
			)
			(layer "B.Fab")
		)
		(fp_line
			(start -0.12065 -0.2794)
			(end -0.12065 -0.3048)
			(stroke
				(width 0.1)
				(type default)
			)
			(layer "B.Fab")
		)
		(fp_line
			(start 0.12065 -0.2794)
			(end -0.12065 -0.2794)
			(stroke
				(width 0.1)
				(type default)
			)
			(layer "B.Fab")
		)
		(fp_line
			(start -0.67945 -0.3048)
			(end -0.67945 0.3048)
			(stroke
				(width 0.1)
				(type default)
			)
			(layer "B.Fab")
		)
		(fp_line
			(start -0.12065 -0.3048)
			(end -0.67945 -0.3048)
			(stroke
				(width 0.1)
				(type default)
			)
			(layer "B.Fab")
		)
		(fp_line
			(start 0.12065 -0.305054)
			(end 0.12065 -0.2794)
			(stroke
				(width 0.1)
				(type default)
			)
			(layer "B.Fab")
		)
		(fp_line
			(start 0.67945 -0.305054)
			(end 0.12065 -0.305054)
			(stroke
				(width 0.1)
				(type default)
			)
			(layer "B.Fab")
		)
		(pad "1" smd circle
			(at 0.40005 0 90)
			(size 0 0)
			(layers "B.Cu" "B.Mask" "B.Paste")
			(net "PRSNT_SSD3_FPGA_R_N")
		)
		(pad "2" smd circle
			(at -0.40005 0 90)
			(size 0 0)
			(layers "B.Cu" "B.Mask" "B.Paste")
			(net "PRSNT_SSD3_FPGA_N")
		)
	)
	(footprint ""
		(layer "B.Cu")
		(at 109.97565 -293.506906 90)
		(property "Reference" "PC86"
			(at 0 0 90)
			(layer "B.SilkS")
			(hide yes)
			(effects
				(font
					(size 1.27 1.27)
				)
				(justify mirror)
			)
		)
		(property "Value" ""
			(at 0 0 90)
			(layer "B.Fab")
			(effects
				(font
					(size 1.27 1.27)
				)
				(justify mirror)
			)
		)
		(duplicate_pad_numbers_are_jumpers no)
		(fp_line
			(start 1.524 -0.762)
			(end -1.524 -0.762)
			(stroke
				(width 0.1524)
				(type default)
			)
			(layer "B.SilkS")
		)
		(fp_line
			(start -1.524 -0.762)
			(end -1.524 0.762)
			(stroke
				(width 0.1524)
				(type default)
			)
			(layer "B.SilkS")
		)
		(fp_line
			(start 1.524 0.762)
			(end 1.524 -0.762)
			(stroke
				(width 0.1524)
				(type default)
			)
			(layer "B.SilkS")
		)
		(fp_line
			(start -1.524 0.762)
			(end 1.524 0.762)
			(stroke
				(width 0.1524)
				(type default)
			)
			(layer "B.SilkS")
		)
		(fp_line
			(start 1.1049 -0.724916)
			(end 1.1049 0.724916)
			(stroke
				(width 0.1)
				(type default)
			)
			(layer "B.Fab")
		)
		(fp_line
			(start -1.1049 -0.724916)
			(end 1.1049 -0.724916)
			(stroke
				(width 0.1)
				(type default)
			)
			(layer "B.Fab")
		)
		(fp_line
			(start 1.1049 0.724916)
			(end -1.1049 0.724916)
			(stroke
				(width 0.1)
				(type default)
			)
			(layer "B.Fab")
		)
		(fp_line
			(start -1.1049 0.724916)
			(end -1.1049 -0.724916)
			(stroke
				(width 0.1)
				(type default)
			)
			(layer "B.Fab")
		)
		(pad "1" smd rect
			(at 0.889 0 90)
			(size 1.016 1.27)
			(layers "B.Cu" "B.Mask" "B.Paste")
			(net "P0V8_PEX0")
		)
		(pad "2" smd rect
			(at -0.889 0 90)
			(size 1.016 1.27)
			(layers "B.Cu" "B.Mask" "B.Paste")
			(net "GND")
		)
	)
	(footprint ""
		(layer "B.Cu")
		(at 180.50002 -288.299906 90)
		(property "Reference" "C3095"
			(at 0 0 90)
			(layer "B.SilkS")
			(hide yes)
			(effects
				(font
					(size 1.27 1.27)
				)
				(justify mirror)
			)
		)
		(property "Value" ""
			(at 0 0 90)
			(layer "B.Fab")
			(effects
				(font
					(size 1.27 1.27)
				)
				(justify mirror)
			)
		)
		(duplicate_pad_numbers_are_jumpers no)
		(fp_line
			(start 0.299974 -0.150114)
			(end -0.299974 -0.150114)
			(stroke
				(width 0.1)
				(type default)
			)
			(layer "B.Fab")
		)
		(fp_line
			(start -0.299974 -0.150114)
			(end -0.299974 0.150114)
			(stroke
				(width 0.1)
				(type default)
			)
			(layer "B.Fab")
		)
		(fp_line
			(start 0.299974 0.150114)
			(end 0.299974 -0.150114)
			(stroke
				(width 0.1)
				(type default)
			)
			(layer "B.Fab")
		)
		(fp_line
			(start -0.299974 0.150114)
			(end 0.299974 0.150114)
			(stroke
				(width 0.1)
				(type default)
			)
			(layer "B.Fab")
		)
		(pad "1" smd rect
			(at 0.2667 0 270)
			(size 0.3048 0.381)
			(layers "B.Cu" "B.Mask" "B.Paste")
			(net "P1V25_PEX1")
		)
		(pad "2" smd rect
			(at -0.2667 0 270)
			(size 0.3048 0.381)
			(layers "B.Cu" "B.Mask" "B.Paste")
			(net "GND")
		)
	)
	(footprint ""
		(layer "B.Cu")
		(at 283.299916 -299.699934 -90)
		(property "Reference" "C1677"
			(at 0 0 90)
			(layer "B.SilkS")
			(hide yes)
			(effects
				(font
					(size 1.27 1.27)
				)
				(justify mirror)
			)
		)
		(property "Value" ""
			(at 0 0 90)
			(layer "B.Fab")
			(effects
				(font
					(size 1.27 1.27)
				)
				(justify mirror)
			)
		)
		(duplicate_pad_numbers_are_jumpers no)
		(fp_line
			(start -0.299974 0.150114)
			(end 0.299974 0.150114)
			(stroke
				(width 0.1)
				(type default)
			)
			(layer "B.Fab")
		)
		(fp_line
			(start 0.299974 0.150114)
			(end 0.299974 -0.150114)
			(stroke
				(width 0.1)
				(type default)
			)
			(layer "B.Fab")
		)
		(fp_line
			(start -0.299974 -0.150114)
			(end -0.299974 0.150114)
			(stroke
				(width 0.1)
				(type default)
			)
			(layer "B.Fab")
		)
		(fp_line
			(start 0.299974 -0.150114)
			(end -0.299974 -0.150114)
			(stroke
				(width 0.1)
				(type default)
			)
			(layer "B.Fab")
		)
		(pad "1" smd rect
			(at 0.2667 0 90)
			(size 0.3048 0.381)
			(layers "B.Cu" "B.Mask" "B.Paste")
			(net "P0V8_SERDES_VDDA_PEX2")
		)
		(pad "2" smd rect
			(at -0.2667 0 90)
			(size 0.3048 0.381)
			(layers "B.Cu" "B.Mask" "B.Paste")
			(net "GND")
		)
	)
	(footprint ""
		(layer "B.Cu")
		(at 73.271634 -114.592608)
		(property "Reference" "C870"
			(at 0 0 0)
			(layer "B.SilkS")
			(hide yes)
			(effects
				(font
					(size 1.27 1.27)
				)
				(justify mirror)
			)
		)
		(property "Value" ""
			(at 0 0 0)
			(layer "B.Fab")
			(effects
				(font
					(size 1.27 1.27)
				)
				(justify mirror)
			)
		)
		(duplicate_pad_numbers_are_jumpers no)
		(fp_line
			(start -0.7874 -0.4064)
			(end -0.7874 0.4064)
			(stroke
				(width 0.1524)
				(type default)
			)
			(layer "B.SilkS")
		)
		(fp_line
			(start -0.7874 0.4064)
			(end 0.7874 0.4064)
			(stroke
				(width 0.1524)
				(type default)
			)
			(layer "B.SilkS")
		)
		(fp_line
			(start 0.7874 -0.4064)
			(end -0.7874 -0.4064)
			(stroke
				(width 0.1524)
				(type default)
			)
			(layer "B.SilkS")
		)
		(fp_line
			(start 0.7874 0.4064)
			(end 0.7874 -0.4064)
			(stroke
				(width 0.1524)
				(type default)
			)
			(layer "B.SilkS")
		)
		(fp_line
			(start -0.67945 -0.3048)
			(end -0.67945 0.3048)
			(stroke
				(width 0.1)
				(type default)
			)
			(layer "B.Fab")
		)
		(fp_line
			(start -0.67945 0.3048)
			(end -0.120396 0.3048)
			(stroke
				(width 0.1)
				(type default)
			)
			(layer "B.Fab")
		)
		(fp_line
			(start -0.12065 -0.3048)
			(end -0.67945 -0.3048)
			(stroke
				(width 0.1)
				(type default)
			)
			(layer "B.Fab")
		)
		(fp_line
			(start -0.12065 -0.2794)
			(end -0.12065 -0.3048)
			(stroke
				(width 0.1)
				(type default)
			)
			(layer "B.Fab")
		)
		(fp_line
			(start -0.120396 0.2794)
			(end 0.12065 0.2794)
			(stroke
				(width 0.1)
				(type default)
			)
			(layer "B.Fab")
		)
		(fp_line
			(start -0.120396 0.3048)
			(end -0.120396 0.2794)
			(stroke
				(width 0.1)
				(type default)
			)
			(layer "B.Fab")
		)
		(fp_line
			(start 0.12065 -0.305054)
			(end 0.12065 -0.2794)
			(stroke
				(width 0.1)
				(type default)
			)
			(layer "B.Fab")
		)
		(fp_line
			(start 0.12065 -0.2794)
			(end -0.12065 -0.2794)
			(stroke
				(width 0.1)
				(type default)
			)
			(layer "B.Fab")
		)
		(fp_line
			(start 0.12065 0.2794)
			(end 0.12065 0.3048)
			(stroke
				(width 0.1)
				(type default)
			)
			(layer "B.Fab")
		)
		(fp_line
			(start 0.12065 0.3048)
			(end 0.67945 0.3048)
			(stroke
				(width 0.1)
				(type default)
			)
			(layer "B.Fab")
		)
		(fp_line
			(start 0.67945 -0.305054)
			(end 0.12065 -0.305054)
			(stroke
				(width 0.1)
				(type default)
			)
			(layer "B.Fab")
		)
		(fp_line
			(start 0.67945 0.3048)
			(end 0.67945 -0.305054)
			(stroke
				(width 0.1)
				(type default)
			)
			(layer "B.Fab")
		)
		(pad "1" smd circle
			(at 0.40005 0 180)
			(size 0 0)
			(layers "B.Cu" "B.Mask" "B.Paste")
			(net "P3V3_NIC1")
		)
		(pad "2" smd circle
			(at -0.40005 0 180)
			(size 0 0)
			(layers "B.Cu" "B.Mask" "B.Paste")
			(net "GND")
		)
	)
)
